# T6G (Grand Teton) — schematic netlist excerpt (pin names and nets, part order shuffled) for the footprints in the layout excerpt that follows; sources: Cadence DE-HDL packaged netlist, KiCad conversion of 04192023_DAF0TMB3IC0_F0TG_MB_C_brd_V02_OCP.brd

R6155  Q_RES  0 5% CHIP  pkg 0201LF  page 113 : A = P2E_MB_BMC_TX_C_DN<0> ; B = P2E_MB_BMC_TX_C_R2_DN<0>
PC6533  Q_CAP  0.1UF 25V 10% X7R  pkg 0402  page 361 : A = P1V8_CPU1_RT_1D ; B = GND
R3570  Q_RES  10 1% CHIP  pkg 0402LF  page 237 : A = P3V3_OCP_V3_2_R ; B = VSENSE_P12V_INA230_3_INP

(kicad_pcb
	(version 20260206)
	(generator "pcbnew")
	(generator_version "10.0")
	(general
		(thickness 1.6)
		(legacy_teardrops no)
	)
	(paper "A4")
	(title_block
		(title "04192023_DAF0TMB3IC0_F0TG_MB_C_brd_V02_OCP.brd")
		(comment 1 "Grand Teton / footprints 4886-4888 of 8354")
	)
	(layers
		(0 "F.Cu" signal "TOP")
		(4 "In1.Cu" signal "GND")
		(6 "In2.Cu" signal "IN1")
		(8 "In3.Cu" signal "GND1")
		(10 "In4.Cu" signal "IN2")
		(12 "In5.Cu" signal "GND2")
		(14 "In6.Cu" signal "IN3")
		(16 "In7.Cu" signal "GND3")
		(18 "In8.Cu" signal "VCC")
		(20 "In9.Cu" signal "VCC1")
		(22 "In10.Cu" signal "GND4")
		(24 "In11.Cu" signal "IN4")
		(26 "In12.Cu" signal "GND5")
		(28 "In13.Cu" signal "IN5")
		(30 "In14.Cu" signal "GND6")
		(32 "In15.Cu" signal "IN6")
		(34 "In16.Cu" signal "GND7")
		(2 "B.Cu" signal "BOTTOM")
		(9 "F.Adhes" user "F.Adhesive")
		(11 "B.Adhes" user "B.Adhesive")
		(13 "F.Paste" user "Package Geometry/Pastemask Top")
		(15 "B.Paste" user "Package Geometry/Pastemask Bottom")
		(5 "F.SilkS" user "Ref Des/Silkscreen Top")
		(7 "B.SilkS" user "Ref Des/Silkscreen Bottom")
		(1 "F.Mask" user "Board Geometry/Soldermask Top")
		(3 "B.Mask" user "Board Geometry/Soldermask Bottom")
		(17 "Dwgs.User" user "User.Drawings")
		(19 "Cmts.User" user "User.Comments")
		(21 "Eco1.User" user "User.Eco1")
		(23 "Eco2.User" user "User.Eco2")
		(25 "Edge.Cuts" user "Board Geometry/Outline")
		(27 "Margin" user)
		(31 "F.CrtYd" user "Package Geometry/Place Bound Top")
		(29 "B.CrtYd" user "Package Geometry/Place Bound Bottom")
		(35 "F.Fab" user "Ref Des/Assembly Top")
		(33 "B.Fab" user "Ref Des/Assembly Bottom")
	)
	(footprint ""
		(layer "F.Cu")
		(at 39.842694 -423.21734)
		(property "Reference" "R6155"
			(at 0 0 0)
			(layer "F.SilkS")
			(hide yes)
			(effects
				(font
					(size 1.27 1.27)
				)
			)
		)
		(property "Value" ""
			(at 0 0 0)
			(layer "F.Fab")
			(effects
				(font
					(size 1.27 1.27)
				)
			)
		)
		(duplicate_pad_numbers_are_jumpers no)
		(fp_line
			(start -0.32512 -0.175006)
			(end 0.32512 -0.175006)
			(stroke
				(width 0.1)
				(type default)
			)
			(layer "F.Fab")
		)
		(fp_line
			(start -0.32512 0.175006)
			(end -0.32512 -0.175006)
			(stroke
				(width 0.1)
				(type default)
			)
			(layer "F.Fab")
		)
		(fp_line
			(start 0.32512 -0.175006)
			(end 0.32512 0.175006)
			(stroke
				(width 0.1)
				(type default)
			)
			(layer "F.Fab")
		)
		(fp_line
			(start 0.32512 0.175006)
			(end -0.32512 0.175006)
			(stroke
				(width 0.1)
				(type default)
			)
			(layer "F.Fab")
		)
		(pad "1" smd rect
			(at -0.2667 0)
			(size 0.3048 0.381)
			(layers "F.Cu" "F.Mask" "F.Paste")
			(net "P2E_MB_BMC_TX_C_DN<0>")
		)
		(pad "2" smd rect
			(at 0.2667 0 180)
			(size 0.3048 0.381)
			(layers "F.Cu" "F.Mask" "F.Paste")
			(net "P2E_MB_BMC_TX_C_R2_DN<0>")
		)
	)
	(footprint ""
		(layer "F.Cu")
		(at 222.738442 -315.95568 90)
		(property "Reference" "PC6533"
			(at 0 0 90)
			(layer "F.SilkS")
			(hide yes)
			(effects
				(font
					(size 1.27 1.27)
				)
			)
		)
		(property "Value" ""
			(at 0 0 90)
			(layer "F.Fab")
			(effects
				(font
					(size 1.27 1.27)
				)
			)
		)
		(duplicate_pad_numbers_are_jumpers no)
		(fp_line
			(start 0.7874 -0.4064)
			(end 0.7874 0.4064)
			(stroke
				(width 0.1524)
				(type default)
			)
			(layer "F.SilkS")
		)
		(fp_line
			(start -0.7874 -0.4064)
			(end 0.7874 -0.4064)
			(stroke
				(width 0.1524)
				(type default)
			)
			(layer "F.SilkS")
		)
		(fp_line
			(start 0.7874 0.4064)
			(end -0.7874 0.4064)
			(stroke
				(width 0.1524)
				(type default)
			)
			(layer "F.SilkS")
		)
		(fp_line
			(start -0.7874 0.4064)
			(end -0.7874 -0.4064)
			(stroke
				(width 0.1524)
				(type default)
			)
			(layer "F.SilkS")
		)
		(fp_line
			(start -0.12065 -0.305054)
			(end -0.12065 -0.2794)
			(stroke
				(width 0.1)
				(type default)
			)
			(layer "F.Fab")
		)
		(fp_line
			(start -0.67945 -0.305054)
			(end -0.12065 -0.305054)
			(stroke
				(width 0.1)
				(type default)
			)
			(layer "F.Fab")
		)
		(fp_line
			(start 0.67945 -0.3048)
			(end 0.67945 0.3048)
			(stroke
				(width 0.1)
				(type default)
			)
			(layer "F.Fab")
		)
		(fp_line
			(start 0.12065 -0.3048)
			(end 0.67945 -0.3048)
			(stroke
				(width 0.1)
				(type default)
			)
			(layer "F.Fab")
		)
		(fp_line
			(start 0.12065 -0.2794)
			(end 0.12065 -0.3048)
			(stroke
				(width 0.1)
				(type default)
			)
			(layer "F.Fab")
		)
		(fp_line
			(start -0.12065 -0.2794)
			(end 0.12065 -0.2794)
			(stroke
				(width 0.1)
				(type default)
			)
			(layer "F.Fab")
		)
		(fp_line
			(start 0.120396 0.2794)
			(end -0.12065 0.2794)
			(stroke
				(width 0.1)
				(type default)
			)
			(layer "F.Fab")
		)
		(fp_line
			(start -0.12065 0.2794)
			(end -0.12065 0.3048)
			(stroke
				(width 0.1)
				(type default)
			)
			(layer "F.Fab")
		)
		(fp_line
			(start 0.67945 0.3048)
			(end 0.120396 0.3048)
			(stroke
				(width 0.1)
				(type default)
			)
			(layer "F.Fab")
		)
		(fp_line
			(start 0.120396 0.3048)
			(end 0.120396 0.2794)
			(stroke
				(width 0.1)
				(type default)
			)
			(layer "F.Fab")
		)
		(fp_line
			(start -0.12065 0.3048)
			(end -0.67945 0.3048)
			(stroke
				(width 0.1)
				(type default)
			)
			(layer "F.Fab")
		)
		(fp_line
			(start -0.67945 0.3048)
			(end -0.67945 -0.305054)
			(stroke
				(width 0.1)
				(type default)
			)
			(layer "F.Fab")
		)
		(pad "1" smd circle
			(at -0.40005 0 90)
			(size 0 0)
			(layers "F.Cu" "F.Mask" "F.Paste")
			(net "P1V8_CPU1_RT_1D")
		)
		(pad "2" smd circle
			(at 0.40005 0 90)
			(size 0 0)
			(layers "F.Cu" "F.Mask" "F.Paste")
			(net "GND")
		)
	)
	(footprint ""
		(layer "F.Cu")
		(at 80.223106 -58.890154 180)
		(property "Reference" "R3570"
			(at 0 0 180)
			(layer "F.SilkS")
			(hide yes)
			(effects
				(font
					(size 1.27 1.27)
				)
			)
		)
		(property "Value" ""
			(at 0 0 180)
			(layer "F.Fab")
			(effects
				(font
					(size 1.27 1.27)
				)
			)
		)
		(duplicate_pad_numbers_are_jumpers no)
		(fp_line
			(start 0.7874 0.4064)
			(end -0.7874 0.4064)
			(stroke
				(width 0.1524)
				(type default)
			)
			(layer "F.SilkS")
		)
		(fp_line
			(start 0.7874 -0.4064)
			(end 0.7874 0.4064)
			(stroke
				(width 0.1524)
				(type default)
			)
			(layer "F.SilkS")
		)
		(fp_line
			(start -0.7874 0.4064)
			(end -0.7874 -0.4064)
			(stroke
				(width 0.1524)
				(type default)
			)
			(layer "F.SilkS")
		)
		(fp_line
			(start -0.7874 -0.4064)
			(end 0.7874 -0.4064)
			(stroke
				(width 0.1524)
				(type default)
			)
			(layer "F.SilkS")
		)
		(fp_line
			(start 0.67945 0.3048)
			(end 0.120396 0.3048)
			(stroke
				(width 0.1)
				(type default)
			)
			(layer "F.Fab")
		)
		(fp_line
			(start 0.67945 -0.3048)
			(end 0.67945 0.3048)
			(stroke
				(width 0.1)
				(type default)
			)
			(layer "F.Fab")
		)
		(fp_line
			(start 0.12065 -0.2794)
			(end 0.12065 -0.3048)
			(stroke
				(width 0.1)
				(type default)
			)
			(layer "F.Fab")
		)
		(fp_line
			(start 0.12065 -0.3048)
			(end 0.67945 -0.3048)
			(stroke
				(width 0.1)
				(type default)
			)
			(layer "F.Fab")
		)
		(fp_line
			(start 0.120396 0.3048)
			(end 0.120396 0.2794)
			(stroke
				(width 0.1)
				(type default)
			)
			(layer "F.Fab")
		)
		(fp_line
			(start 0.120396 0.2794)
			(end -0.12065 0.2794)
			(stroke
				(width 0.1)
				(type default)
			)
			(layer "F.Fab")
		)
		(fp_line
			(start -0.12065 0.3048)
			(end -0.67945 0.3048)
			(stroke
				(width 0.1)
				(type default)
			)
			(layer "F.Fab")
		)
		(fp_line
			(start -0.12065 0.2794)
			(end -0.12065 0.3048)
			(stroke
				(width 0.1)
				(type default)
			)
			(layer "F.Fab")
		)
		(fp_line
			(start -0.12065 -0.2794)
			(end 0.12065 -0.2794)
			(stroke
				(width 0.1)
				(type default)
			)
			(layer "F.Fab")
		)
		(fp_line
			(start -0.12065 -0.305054)
			(end -0.12065 -0.2794)
			(stroke
				(width 0.1)
				(type default)
			)
			(layer "F.Fab")
		)
		(fp_line
			(start -0.67945 0.3048)
			(end -0.67945 -0.305054)
			(stroke
				(width 0.1)
				(type default)
			)
			(layer "F.Fab")
		)
		(fp_line
			(start -0.67945 -0.305054)
			(end -0.12065 -0.305054)
			(stroke
				(width 0.1)
				(type default)
			)
			(layer "F.Fab")
		)
		(pad "1" smd circle
			(at -0.40005 0 180)
			(size 0 0)
			(layers "F.Cu" "F.Mask" "F.Paste")
			(net "P3V3_OCP_V3_2_R")
		)
		(pad "2" smd circle
			(at 0.40005 0 180)
			(size 0 0)
			(layers "F.Cu" "F.Mask" "F.Paste")
			(net "VSENSE_P12V_INA230_3_INP")
		)
	)
)
